# S9S_MB_2U (Grand Teton) — schematic netlist excerpt (pin names and nets, part order shuffled) for the footprints in the layout excerpt that follows; sources: Cadence DE-HDL packaged netlist, KiCad conversion of 03242023_DA0F0TMBIJ0_F0T_Motherboard_J_brd_V01_OCP.brd

R982  Q_RES  33.2 1% CHIP  pkg 0402LF  page 222 : A = FM_PVCCFA_EHV_CPU0_R_EN ; B = FM_PVCCFA_EHV_CPU0_EN
PC232_P0_8  Q_CAP  1UF 16V 10% X6S  pkg C0402  page 270 : A = SW_P12V_PVCCIN_CPU0_FLT ; B = GND

(kicad_pcb
	(version 20260206)
	(generator "pcbnew")
	(generator_version "10.0")
	(general
		(thickness 1.6)
		(legacy_teardrops no)
	)
	(paper "A4")
	(title_block
		(title "03242023_DA0F0TMBIJ0_F0T_Motherboard_J_brd_V01_OCP.brd")
		(comment 1 "Grand Teton / footprints 2455-2456 of 6105")
	)
	(layers
		(0 "F.Cu" signal "TOP")
		(4 "In1.Cu" signal "GND")
		(6 "In2.Cu" signal "IN1")
		(8 "In3.Cu" signal "GND1")
		(10 "In4.Cu" signal "IN2")
		(12 "In5.Cu" signal "GND2")
		(14 "In6.Cu" signal "IN3")
		(16 "In7.Cu" signal "GND3")
		(18 "In8.Cu" signal "VCC")
		(20 "In9.Cu" signal "VCC1")
		(22 "In10.Cu" signal "GND4")
		(24 "In11.Cu" signal "IN4")
		(26 "In12.Cu" signal "GND5")
		(28 "In13.Cu" signal "IN5")
		(30 "In14.Cu" signal "GND6")
		(32 "In15.Cu" signal "IN6")
		(34 "In16.Cu" signal "GND7")
		(2 "B.Cu" signal "BOTTOM")
		(9 "F.Adhes" user "F.Adhesive")
		(11 "B.Adhes" user "B.Adhesive")
		(13 "F.Paste" user "Package Geometry/Pastemask Top")
		(15 "B.Paste" user "Package Geometry/Pastemask Bottom")
		(5 "F.SilkS" user "Ref Des/Silkscreen Top")
		(7 "B.SilkS" user "Ref Des/Silkscreen Bottom")
		(1 "F.Mask" user "Board Geometry/Soldermask Top")
		(3 "B.Mask" user "Board Geometry/Soldermask Bottom")
		(17 "Dwgs.User" user "User.Drawings")
		(19 "Cmts.User" user "User.Comments")
		(21 "Eco1.User" user "User.Eco1")
		(23 "Eco2.User" user "User.Eco2")
		(25 "Edge.Cuts" user "Board Geometry/Outline")
		(27 "Margin" user)
		(31 "F.CrtYd" user "Package Geometry/Place Bound Top")
		(29 "B.CrtYd" user "Package Geometry/Place Bound Bottom")
		(35 "F.Fab" user "Ref Des/Assembly Top")
		(33 "B.Fab" user "Ref Des/Assembly Bottom")
	)
	(footprint ""
		(layer "F.Cu")
		(at 157.02788 -118.836948 180)
		(property "Reference" "R982"
			(at 0 0 180)
			(layer "F.SilkS")
			(hide yes)
			(effects
				(font
					(size 1.27 1.27)
				)
			)
		)
		(property "Value" ""
			(at 0 0 180)
			(layer "F.Fab")
			(effects
				(font
					(size 1.27 1.27)
				)
			)
		)
		(duplicate_pad_numbers_are_jumpers no)
		(fp_line
			(start 0.7874 0.4064)
			(end -0.7874 0.4064)
			(stroke
				(width 0.1524)
				(type default)
			)
			(layer "F.SilkS")
		)
		(fp_line
			(start 0.7874 -0.4064)
			(end 0.7874 0.4064)
			(stroke
				(width 0.1524)
				(type default)
			)
			(layer "F.SilkS")
		)
		(fp_line
			(start -0.7874 0.4064)
			(end -0.7874 -0.4064)
			(stroke
				(width 0.1524)
				(type default)
			)
			(layer "F.SilkS")
		)
		(fp_line
			(start -0.7874 -0.4064)
			(end 0.7874 -0.4064)
			(stroke
				(width 0.1524)
				(type default)
			)
			(layer "F.SilkS")
		)
		(fp_line
			(start 0.67945 0.3048)
			(end 0.120396 0.3048)
			(stroke
				(width 0.1)
				(type default)
			)
			(layer "F.Fab")
		)
		(fp_line
			(start 0.67945 -0.3048)
			(end 0.67945 0.3048)
			(stroke
				(width 0.1)
				(type default)
			)
			(layer "F.Fab")
		)
		(fp_line
			(start 0.12065 -0.2794)
			(end 0.12065 -0.3048)
			(stroke
				(width 0.1)
				(type default)
			)
			(layer "F.Fab")
		)
		(fp_line
			(start 0.12065 -0.3048)
			(end 0.67945 -0.3048)
			(stroke
				(width 0.1)
				(type default)
			)
			(layer "F.Fab")
		)
		(fp_line
			(start 0.120396 0.3048)
			(end 0.120396 0.2794)
			(stroke
				(width 0.1)
				(type default)
			)
			(layer "F.Fab")
		)
		(fp_line
			(start 0.120396 0.2794)
			(end -0.12065 0.2794)
			(stroke
				(width 0.1)
				(type default)
			)
			(layer "F.Fab")
		)
		(fp_line
			(start -0.12065 0.3048)
			(end -0.67945 0.3048)
			(stroke
				(width 0.1)
				(type default)
			)
			(layer "F.Fab")
		)
		(fp_line
			(start -0.12065 0.2794)
			(end -0.12065 0.3048)
			(stroke
				(width 0.1)
				(type default)
			)
			(layer "F.Fab")
		)
		(fp_line
			(start -0.12065 -0.2794)
			(end 0.12065 -0.2794)
			(stroke
				(width 0.1)
				(type default)
			)
			(layer "F.Fab")
		)
		(fp_line
			(start -0.12065 -0.305054)
			(end -0.12065 -0.2794)
			(stroke
				(width 0.1)
				(type default)
			)
			(layer "F.Fab")
		)
		(fp_line
			(start -0.67945 0.3048)
			(end -0.67945 -0.305054)
			(stroke
				(width 0.1)
				(type default)
			)
			(layer "F.Fab")
		)
		(fp_line
			(start -0.67945 -0.305054)
			(end -0.12065 -0.305054)
			(stroke
				(width 0.1)
				(type default)
			)
			(layer "F.Fab")
		)
		(pad "1" smd circle
			(at -0.40005 0 180)
			(size 0 0)
			(layers "F.Cu" "F.Mask" "F.Paste")
			(net "FM_PVCCFA_EHV_CPU0_R_EN")
		)
		(pad "2" smd circle
			(at 0.40005 0 180)
			(size 0 0)
			(layers "F.Cu" "F.Mask" "F.Paste")
			(net "FM_PVCCFA_EHV_CPU0_EN")
		)
	)
	(footprint ""
		(layer "F.Cu")
		(at 389.312658 -343.018872 -90)
		(property "Reference" "PC232_P0_8"
			(at 0 0 270)
			(layer "F.SilkS")
			(hide yes)
			(effects
				(font
					(size 1.27 1.27)
				)
			)
		)
		(property "Value" ""
			(at 0 0 270)
			(layer "F.Fab")
			(effects
				(font
					(size 1.27 1.27)
				)
			)
		)
		(duplicate_pad_numbers_are_jumpers no)
		(fp_line
			(start -0.7874 0.4064)
			(end -0.7874 -0.4064)
			(stroke
				(width 0.1524)
				(type default)
			)
			(layer "F.SilkS")
		)
		(fp_line
			(start 0.7874 0.4064)
			(end -0.7874 0.4064)
			(stroke
				(width 0.1524)
				(type default)
			)
			(layer "F.SilkS")
		)
		(fp_line
			(start -0.7874 -0.4064)
			(end 0.7874 -0.4064)
			(stroke
				(width 0.1524)
				(type default)
			)
			(layer "F.SilkS")
		)
		(fp_line
			(start 0.7874 -0.4064)
			(end 0.7874 0.4064)
			(stroke
				(width 0.1524)
				(type default)
			)
			(layer "F.SilkS")
		)
		(fp_line
			(start -0.67945 0.3048)
			(end -0.67945 -0.305054)
			(stroke
				(width 0.1)
				(type default)
			)
			(layer "F.Fab")
		)
		(fp_line
			(start -0.12065 0.3048)
			(end -0.67945 0.3048)
			(stroke
				(width 0.1)
				(type default)
			)
			(layer "F.Fab")
		)
		(fp_line
			(start 0.120396 0.3048)
			(end 0.120396 0.2794)
			(stroke
				(width 0.1)
				(type default)
			)
			(layer "F.Fab")
		)
		(fp_line
			(start 0.67945 0.3048)
			(end 0.120396 0.3048)
			(stroke
				(width 0.1)
				(type default)
			)
			(layer "F.Fab")
		)
		(fp_line
			(start -0.12065 0.2794)
			(end -0.12065 0.3048)
			(stroke
				(width 0.1)
				(type default)
			)
			(layer "F.Fab")
		)
		(fp_line
			(start 0.120396 0.2794)
			(end -0.12065 0.2794)
			(stroke
				(width 0.1)
				(type default)
			)
			(layer "F.Fab")
		)
		(fp_line
			(start -0.12065 -0.2794)
			(end 0.12065 -0.2794)
			(stroke
				(width 0.1)
				(type default)
			)
			(layer "F.Fab")
		)
		(fp_line
			(start 0.12065 -0.2794)
			(end 0.12065 -0.3048)
			(stroke
				(width 0.1)
				(type default)
			)
			(layer "F.Fab")
		)
		(fp_line
			(start 0.12065 -0.3048)
			(end 0.67945 -0.3048)
			(stroke
				(width 0.1)
				(type default)
			)
			(layer "F.Fab")
		)
		(fp_line
			(start 0.67945 -0.3048)
			(end 0.67945 0.3048)
			(stroke
				(width 0.1)
				(type default)
			)
			(layer "F.Fab")
		)
		(fp_line
			(start -0.67945 -0.305054)
			(end -0.12065 -0.305054)
			(stroke
				(width 0.1)
				(type default)
			)
			(layer "F.Fab")
		)
		(fp_line
			(start -0.12065 -0.305054)
			(end -0.12065 -0.2794)
			(stroke
				(width 0.1)
				(type default)
			)
			(layer "F.Fab")
		)
		(pad "1" smd circle
			(at -0.40005 0 270)
			(size 0 0)
			(layers "F.Cu" "F.Mask" "F.Paste")
			(net "SW_P12V_PVCCIN_CPU0_FLT")
		)
		(pad "2" smd circle
			(at 0.40005 0 270)
			(size 0 0)
			(layers "F.Cu" "F.Mask" "F.Paste")
			(net "GND")
		)
	)
)
